# S9S_MB_2U (Grand Teton) — schematic netlist excerpt (pin names and nets, part order shuffled) for the footprints in the layout excerpt that follows; sources: Cadence DE-HDL packaged netlist, KiCad conversion of 03242023_DA0F0TMBIJ0_F0T_Motherboard_J_brd_V01_OCP.brd

R4476  Q_RES  49.9 1% CHIP  pkg 0402LF  page 211 : A = FM_PLD_CLKS_DEV_EN ; B = FM_9ZXL045_DEV_EN
R3436  Q_RES  4.7K 5% CHIP  pkg 0402LF  page 147 : A = P3V3_AUX ; B = GPU_HMC_PRSNT_ISO_N

(kicad_pcb
	(version 20260206)
	(generator "pcbnew")
	(generator_version "10.0")
	(general
		(thickness 1.6)
		(legacy_teardrops no)
	)
	(paper "A4")
	(title_block
		(title "03242023_DA0F0TMBIJ0_F0T_Motherboard_J_brd_V01_OCP.brd")
		(comment 1 "Grand Teton / footprints 804-805 of 6105")
	)
	(layers
		(0 "F.Cu" signal "TOP")
		(4 "In1.Cu" signal "GND")
		(6 "In2.Cu" signal "IN1")
		(8 "In3.Cu" signal "GND1")
		(10 "In4.Cu" signal "IN2")
		(12 "In5.Cu" signal "GND2")
		(14 "In6.Cu" signal "IN3")
		(16 "In7.Cu" signal "GND3")
		(18 "In8.Cu" signal "VCC")
		(20 "In9.Cu" signal "VCC1")
		(22 "In10.Cu" signal "GND4")
		(24 "In11.Cu" signal "IN4")
		(26 "In12.Cu" signal "GND5")
		(28 "In13.Cu" signal "IN5")
		(30 "In14.Cu" signal "GND6")
		(32 "In15.Cu" signal "IN6")
		(34 "In16.Cu" signal "GND7")
		(2 "B.Cu" signal "BOTTOM")
		(9 "F.Adhes" user "F.Adhesive")
		(11 "B.Adhes" user "B.Adhesive")
		(13 "F.Paste" user "Package Geometry/Pastemask Top")
		(15 "B.Paste" user "Package Geometry/Pastemask Bottom")
		(5 "F.SilkS" user "Ref Des/Silkscreen Top")
		(7 "B.SilkS" user "Ref Des/Silkscreen Bottom")
		(1 "F.Mask" user "Board Geometry/Soldermask Top")
		(3 "B.Mask" user "Board Geometry/Soldermask Bottom")
		(17 "Dwgs.User" user "User.Drawings")
		(19 "Cmts.User" user "User.Comments")
		(21 "Eco1.User" user "User.Eco1")
		(23 "Eco2.User" user "User.Eco2")
		(25 "Edge.Cuts" user "Board Geometry/Outline")
		(27 "Margin" user)
		(31 "F.CrtYd" user "Package Geometry/Place Bound Top")
		(29 "B.CrtYd" user "Package Geometry/Place Bound Bottom")
		(35 "F.Fab" user "Ref Des/Assembly Top")
		(33 "B.Fab" user "Ref Des/Assembly Bottom")
	)
	(footprint ""
		(layer "F.Cu")
		(at 176.078388 -416.729418 180)
		(property "Reference" "R3436"
			(at 0 0 180)
			(layer "F.SilkS")
			(hide yes)
			(effects
				(font
					(size 1.27 1.27)
				)
			)
		)
		(property "Value" ""
			(at 0 0 180)
			(layer "F.Fab")
			(effects
				(font
					(size 1.27 1.27)
				)
			)
		)
		(duplicate_pad_numbers_are_jumpers no)
		(fp_line
			(start 0.7874 0.4064)
			(end -0.7874 0.4064)
			(stroke
				(width 0.1524)
				(type default)
			)
			(layer "F.SilkS")
		)
		(fp_line
			(start 0.7874 -0.4064)
			(end 0.7874 0.4064)
			(stroke
				(width 0.1524)
				(type default)
			)
			(layer "F.SilkS")
		)
		(fp_line
			(start -0.7874 0.4064)
			(end -0.7874 -0.4064)
			(stroke
				(width 0.1524)
				(type default)
			)
			(layer "F.SilkS")
		)
		(fp_line
			(start -0.7874 -0.4064)
			(end 0.7874 -0.4064)
			(stroke
				(width 0.1524)
				(type default)
			)
			(layer "F.SilkS")
		)
		(fp_line
			(start 0.67945 0.3048)
			(end 0.120396 0.3048)
			(stroke
				(width 0.1)
				(type default)
			)
			(layer "F.Fab")
		)
		(fp_line
			(start 0.67945 -0.3048)
			(end 0.67945 0.3048)
			(stroke
				(width 0.1)
				(type default)
			)
			(layer "F.Fab")
		)
		(fp_line
			(start 0.12065 -0.2794)
			(end 0.12065 -0.3048)
			(stroke
				(width 0.1)
				(type default)
			)
			(layer "F.Fab")
		)
		(fp_line
			(start 0.12065 -0.3048)
			(end 0.67945 -0.3048)
			(stroke
				(width 0.1)
				(type default)
			)
			(layer "F.Fab")
		)
		(fp_line
			(start 0.120396 0.3048)
			(end 0.120396 0.2794)
			(stroke
				(width 0.1)
				(type default)
			)
			(layer "F.Fab")
		)
		(fp_line
			(start 0.120396 0.2794)
			(end -0.12065 0.2794)
			(stroke
				(width 0.1)
				(type default)
			)
			(layer "F.Fab")
		)
		(fp_line
			(start -0.12065 0.3048)
			(end -0.67945 0.3048)
			(stroke
				(width 0.1)
				(type default)
			)
			(layer "F.Fab")
		)
		(fp_line
			(start -0.12065 0.2794)
			(end -0.12065 0.3048)
			(stroke
				(width 0.1)
				(type default)
			)
			(layer "F.Fab")
		)
		(fp_line
			(start -0.12065 -0.2794)
			(end 0.12065 -0.2794)
			(stroke
				(width 0.1)
				(type default)
			)
			(layer "F.Fab")
		)
		(fp_line
			(start -0.12065 -0.305054)
			(end -0.12065 -0.2794)
			(stroke
				(width 0.1)
				(type default)
			)
			(layer "F.Fab")
		)
		(fp_line
			(start -0.67945 0.3048)
			(end -0.67945 -0.305054)
			(stroke
				(width 0.1)
				(type default)
			)
			(layer "F.Fab")
		)
		(fp_line
			(start -0.67945 -0.305054)
			(end -0.12065 -0.305054)
			(stroke
				(width 0.1)
				(type default)
			)
			(layer "F.Fab")
		)
		(pad "1" smd circle
			(at -0.40005 0 180)
			(size 0 0)
			(layers "F.Cu" "F.Mask" "F.Paste")
			(net "P3V3_AUX")
		)
		(pad "2" smd circle
			(at 0.40005 0 180)
			(size 0 0)
			(layers "F.Cu" "F.Mask" "F.Paste")
			(net "GPU_HMC_PRSNT_ISO_N")
		)
	)
	(footprint ""
		(layer "F.Cu")
		(at 118.86184 -413.189928 180)
		(property "Reference" "R4476"
			(at 0 0 180)
			(layer "F.SilkS")
			(hide yes)
			(effects
				(font
					(size 1.27 1.27)
				)
			)
		)
		(property "Value" ""
			(at 0 0 180)
			(layer "F.Fab")
			(effects
				(font
					(size 1.27 1.27)
				)
			)
		)
		(duplicate_pad_numbers_are_jumpers no)
		(fp_line
			(start 0.7874 0.4064)
			(end -0.7874 0.4064)
			(stroke
				(width 0.1524)
				(type default)
			)
			(layer "F.SilkS")
		)
		(fp_line
			(start 0.7874 -0.4064)
			(end 0.7874 0.4064)
			(stroke
				(width 0.1524)
				(type default)
			)
			(layer "F.SilkS")
		)
		(fp_line
			(start -0.7874 0.4064)
			(end -0.7874 -0.4064)
			(stroke
				(width 0.1524)
				(type default)
			)
			(layer "F.SilkS")
		)
		(fp_line
			(start -0.7874 -0.4064)
			(end 0.7874 -0.4064)
			(stroke
				(width 0.1524)
				(type default)
			)
			(layer "F.SilkS")
		)
		(fp_line
			(start 0.67945 0.3048)
			(end 0.120396 0.3048)
			(stroke
				(width 0.1)
				(type default)
			)
			(layer "F.Fab")
		)
		(fp_line
			(start 0.67945 -0.3048)
			(end 0.67945 0.3048)
			(stroke
				(width 0.1)
				(type default)
			)
			(layer "F.Fab")
		)
		(fp_line
			(start 0.12065 -0.2794)
			(end 0.12065 -0.3048)
			(stroke
				(width 0.1)
				(type default)
			)
			(layer "F.Fab")
		)
		(fp_line
			(start 0.12065 -0.3048)
			(end 0.67945 -0.3048)
			(stroke
				(width 0.1)
				(type default)
			)
			(layer "F.Fab")
		)
		(fp_line
			(start 0.120396 0.3048)
			(end 0.120396 0.2794)
			(stroke
				(width 0.1)
				(type default)
			)
			(layer "F.Fab")
		)
		(fp_line
			(start 0.120396 0.2794)
			(end -0.12065 0.2794)
			(stroke
				(width 0.1)
				(type default)
			)
			(layer "F.Fab")
		)
		(fp_line
			(start -0.12065 0.3048)
			(end -0.67945 0.3048)
			(stroke
				(width 0.1)
				(type default)
			)
			(layer "F.Fab")
		)
		(fp_line
			(start -0.12065 0.2794)
			(end -0.12065 0.3048)
			(stroke
				(width 0.1)
				(type default)
			)
			(layer "F.Fab")
		)
		(fp_line
			(start -0.12065 -0.2794)
			(end 0.12065 -0.2794)
			(stroke
				(width 0.1)
				(type default)
			)
			(layer "F.Fab")
		)
		(fp_line
			(start -0.12065 -0.305054)
			(end -0.12065 -0.2794)
			(stroke
				(width 0.1)
				(type default)
			)
			(layer "F.Fab")
		)
		(fp_line
			(start -0.67945 0.3048)
			(end -0.67945 -0.305054)
			(stroke
				(width 0.1)
				(type default)
			)
			(layer "F.Fab")
		)
		(fp_line
			(start -0.67945 -0.305054)
			(end -0.12065 -0.305054)
			(stroke
				(width 0.1)
				(type default)
			)
			(layer "F.Fab")
		)
		(pad "1" smd circle
			(at -0.40005 0 180)
			(size 0 0)
			(layers "F.Cu" "F.Mask" "F.Paste")
			(net "FM_PLD_CLKS_DEV_EN")
		)
		(pad "2" smd circle
			(at 0.40005 0 180)
			(size 0 0)
			(layers "F.Cu" "F.Mask" "F.Paste")
			(net "FM_9ZXL045_DEV_EN")
		)
	)
)
